FILE_TYPE = MULTI_PHYS_TABLE;
PART 'FSA3357'
{======================================================================================================================================================================}
:PACK_TYPE|MATERIAL  |PART_NUMBER      = EnvComp |PART_NUMBER   |JEDEC_TYPE       |CLASS  |DESCRIPTION                           |HEIGHT      |COMPONENT_TYPE  | LPID  | SPEED_URL | Status |RPL| AML | Bus_Unit | Days ;
{======================================================================================================================================================================}
'SM'      | 'IC'     | 'C63273-001'(!) = 'YES;YES;CNC;CNC;ok;VLD' | 'C63273-001' | 'SOI8_9_05MA'   | 'IC'  | 'IC,LIN,ANALOG SWITCH,SO-8,FSA3357K' | '0.035 IN' | 'SUB50'        | '733' | 'http://speed.intel.com:8081/speed/module/pdm/item/pdm_item_detail_direct.asp?item_cde=C63273-001&item_rev=01&url_param=unused' | 'Design' | 'NO' | '1' | 'SMO_IC' | '???' 
'SM'      | 'EMPTY'  | 'C63273-001'(!) = 'YES;YES;CNC;CNC;ok;VLD' | 'C63273-001' | 'SOI8_9_05MA'   | 'IO'  | 'IC,LIN,ANALOG SWITCH,SO-8,FSA3357K' | '0.035 IN' | 'SUB50'        | '733' | 'http://speed.intel.com:8081/speed/module/pdm/item/pdm_item_detail_direct.asp?item_cde=C63273-001&item_rev=01&url_param=unused' | 'Design' | 'NO' | '1' | 'SMO_IC' | '???' 
END_PART
END.
